(kicad_pcb
	(version 20260206)
	(generator "pcbnew")
	(generator_version "10.0")
	(general
		(thickness 1.6)
		(legacy_teardrops no)
	)
	(paper "A4")
	(title_block
		(title "01162023_DA0F0TEBIF0_F0T_Expander_BD_F_brd_V02_OCP.brd")
		(comment 1 "Grand Teton / footprint 1849 of 9728 (U5), pads 111-223 of 256")
	)
	(layers
		(0 "F.Cu" signal "TOP")
		(4 "In1.Cu" signal "GND")
		(6 "In2.Cu" signal "VCC")
		(8 "In3.Cu" signal "VCC1")
		(10 "In4.Cu" signal "GND1")
		(12 "In5.Cu" signal "IN1")
		(14 "In6.Cu" signal "GND2")
		(16 "In7.Cu" signal "IN2")
		(18 "In8.Cu" signal "GND3")
		(20 "In9.Cu" signal "IN3")
		(22 "In10.Cu" signal "GND4")
		(24 "In11.Cu" signal "IN4")
		(26 "In12.Cu" signal "GND5")
		(28 "In13.Cu" signal "IN5")
		(30 "In14.Cu" signal "GND6")
		(32 "In15.Cu" signal "IN6")
		(34 "In16.Cu" signal "GND7")
		(2 "B.Cu" signal "BOTTOM")
		(9 "F.Adhes" user "F.Adhesive")
		(11 "B.Adhes" user "B.Adhesive")
		(13 "F.Paste" user "Package Geometry/Pastemask Top")
		(15 "B.Paste" user "Package Geometry/Pastemask Bottom")
		(5 "F.SilkS" user "Ref Des/Silkscreen Top")
		(7 "B.SilkS" user "Ref Des/Silkscreen Bottom")
		(1 "F.Mask" user "Board Geometry/Soldermask Top")
		(3 "B.Mask" user "Board Geometry/Soldermask Bottom")
		(17 "Dwgs.User" user "User.Drawings")
		(19 "Cmts.User" user "User.Comments")
		(21 "Eco1.User" user "User.Eco1")
		(23 "Eco2.User" user "User.Eco2")
		(25 "Edge.Cuts" user "Board Geometry/Outline")
		(27 "Margin" user)
		(31 "F.CrtYd" user "Package Geometry/Place Bound Top")
		(29 "B.CrtYd" user "Package Geometry/Place Bound Bottom")
		(35 "F.Fab" user "Ref Des/Assembly Top")
		(33 "B.Fab" user "Ref Des/Assembly Bottom")
	)
	(footprint ""
		(layer "F.Cu")
		(at 229.467664 -218.70416 180)
		(property "Reference" "U5"
			(at -4.517136 -8.03783 0)
			(unlocked yes)
			(layer "F.SilkS")
			(effects
				(font
					(size 0.7874 0.5842)
					(thickness 0.1524)
				)
				(justify left)
			)
		)
		(property "Value" ""
			(at 0 0 180)
			(layer "F.Fab")
			(effects
				(font
					(size 1.27 1.27)
				)
			)
		)
		(duplicate_pad_numbers_are_jumpers no)
		(pad "G15" smd circle
			(at 5.199888 -1.199896 180)
			(size 0.4064 0.4064)
			(layers "F.Cu" "F.Mask" "F.Paste")
			(net "SMB_NIC6_SDA")
		)
		(pad "G16" smd circle
			(at 5.999988 -1.199896 180)
			(size 0.4064 0.4064)
			(layers "F.Cu" "F.Mask" "F.Paste")
			(net "SMB_NIC7_SDA")
		)
		(pad "H1" smd circle
			(at -5.999988 -0.40005 180)
			(size 0.4064 0.4064)
			(layers "F.Cu" "F.Mask" "F.Paste")
			(net "P1V8_PLL0_PEX3_SCALED")
		)
		(pad "H2" smd circle
			(at -5.199888 -0.40005 180)
			(size 0.4064 0.4064)
			(layers "F.Cu" "F.Mask" "F.Paste")
			(net "P1V8_PLL0_PEX2_SCALED")
		)
		(pad "H3" smd circle
			(at -4.400042 -0.40005 180)
			(size 0.4064 0.4064)
			(layers "F.Cu" "F.Mask" "F.Paste")
			(net "BIC_ADCVREFN1")
		)
		(pad "H4" smd circle
			(at -3.599942 -0.40005 180)
			(size 0.4064 0.4064)
			(layers "F.Cu" "F.Mask" "F.Paste")
			(net "P3V3_AUX")
		)
		(pad "H5" smd circle
			(at -2.800096 -0.40005 180)
			(size 0.4064 0.4064)
			(layers "F.Cu" "F.Mask" "F.Paste")
			(net "P1V2_AUX")
		)
		(pad "H6" smd circle
			(at -1.999996 -0.40005 180)
			(size 0.4064 0.4064)
			(layers "F.Cu" "F.Mask" "F.Paste")
			(net "GND")
		)
		(pad "H7" smd circle
			(at -1.199896 -0.40005 180)
			(size 0.4064 0.4064)
			(layers "F.Cu" "F.Mask" "F.Paste")
			(net "GND")
		)
		(pad "H8" smd circle
			(at -0.40005 -0.40005 180)
			(size 0.4064 0.4064)
			(layers "F.Cu" "F.Mask" "F.Paste")
			(net "GND")
		)
		(pad "H9" smd circle
			(at 0.40005 -0.40005 180)
			(size 0.4064 0.4064)
			(layers "F.Cu" "F.Mask" "F.Paste")
			(net "GND")
		)
		(pad "H10" smd circle
			(at 1.199896 -0.40005 180)
			(size 0.4064 0.4064)
			(layers "F.Cu" "F.Mask" "F.Paste")
			(net "GND")
		)
		(pad "H11" smd circle
			(at 1.999996 -0.40005 180)
			(size 0.4064 0.4064)
			(layers "F.Cu" "F.Mask" "F.Paste")
			(net "GND")
		)
		(pad "H12" smd circle
			(at 2.800096 -0.40005 180)
			(size 0.4064 0.4064)
			(layers "F.Cu" "F.Mask" "F.Paste")
			(net "P1V2_AUX")
		)
		(pad "H13" smd circle
			(at 3.599942 -0.40005 180)
			(size 0.4064 0.4064)
			(layers "F.Cu" "F.Mask" "F.Paste")
			(net "PECI_VDD")
		)
		(pad "H14" smd circle
			(at 4.400042 -0.40005 180)
			(size 0.4064 0.4064)
			(layers "F.Cu" "F.Mask" "F.Paste")
			(net "BIC_PECI")
		)
		(pad "H15" smd circle
			(at 5.199888 -0.40005 180)
			(size 0.4064 0.4064)
			(layers "F.Cu" "F.Mask" "F.Paste")
			(net "SMB_NIC6_SCL")
		)
		(pad "H16" smd circle
			(at 5.999988 -0.40005 180)
			(size 0.4064 0.4064)
			(layers "F.Cu" "F.Mask" "F.Paste")
			(net "SMB_NIC5_SDA")
		)
		(pad "J1" smd circle
			(at -5.999988 0.40005 180)
			(size 0.4064 0.4064)
			(layers "F.Cu" "F.Mask" "F.Paste")
			(net "HSC_TYPE_ADC_R")
		)
		(pad "J2" smd circle
			(at -5.199888 0.40005 180)
			(size 0.4064 0.4064)
			(layers "F.Cu" "F.Mask" "F.Paste")
			(net "VR_TYPE_ADC_R")
		)
		(pad "J3" smd circle
			(at -4.400042 0.40005 180)
			(size 0.4064 0.4064)
			(layers "F.Cu" "F.Mask" "F.Paste")
			(net "BIC_ADCVREFP1")
		)
		(pad "J4" smd circle
			(at -3.599942 0.40005 180)
			(size 0.4064 0.4064)
			(layers "F.Cu" "F.Mask" "F.Paste")
			(net "ADC_TYPE_ADC_R")
		)
		(pad "J5" smd circle
			(at -2.800096 0.40005 180)
			(size 0.4064 0.4064)
			(layers "F.Cu" "F.Mask" "F.Paste")
			(net "P3V3_BIC_ADCAV33")
		)
		(pad "J6" smd circle
			(at -1.999996 0.40005 180)
			(size 0.4064 0.4064)
			(layers "F.Cu" "F.Mask" "F.Paste")
			(net "GND")
		)
		(pad "J7" smd circle
			(at -1.199896 0.40005 180)
			(size 0.4064 0.4064)
			(layers "F.Cu" "F.Mask" "F.Paste")
			(net "GND")
		)
		(pad "J8" smd circle
			(at -0.40005 0.40005 180)
			(size 0.4064 0.4064)
			(layers "F.Cu" "F.Mask" "F.Paste")
			(net "GND")
		)
		(pad "J9" smd circle
			(at 0.40005 0.40005 180)
			(size 0.4064 0.4064)
			(layers "F.Cu" "F.Mask" "F.Paste")
			(net "GND")
		)
		(pad "J10" smd circle
			(at 1.199896 0.40005 180)
			(size 0.4064 0.4064)
			(layers "F.Cu" "F.Mask" "F.Paste")
			(net "GND")
		)
		(pad "J11" smd circle
			(at 1.999996 0.40005 180)
			(size 0.4064 0.4064)
			(layers "F.Cu" "F.Mask" "F.Paste")
			(net "GND")
		)
		(pad "J12" smd circle
			(at 2.800096 0.40005 180)
			(size 0.4064 0.4064)
			(layers "F.Cu" "F.Mask" "F.Paste")
			(net "P1V2_AUX")
		)
		(pad "J13" smd circle
			(at 3.599942 0.40005 180)
			(size 0.4064 0.4064)
			(layers "F.Cu" "F.Mask" "F.Paste")
			(net "SMB_NIC7_SCL")
		)
		(pad "J14" smd circle
			(at 4.400042 0.40005 180)
			(size 0.4064 0.4064)
			(layers "F.Cu" "F.Mask" "F.Paste")
			(net "SMB_NIC5_SCL")
		)
		(pad "J15" smd circle
			(at 5.199888 0.40005 180)
			(size 0.4064 0.4064)
			(layers "F.Cu" "F.Mask" "F.Paste")
			(net "SMB_NIC4_SDA")
		)
		(pad "J16" smd circle
			(at 5.999988 0.40005 180)
			(size 0.4064 0.4064)
			(layers "F.Cu" "F.Mask" "F.Paste")
			(net "SMB_NIC4_SCL")
		)
		(pad "K1" smd circle
			(at -5.999988 1.199896 180)
			(size 0.4064 0.4064)
			(layers "F.Cu" "F.Mask" "F.Paste")
			(net "SSD12_PWRDIS_BIC")
		)
		(pad "K2" smd circle
			(at -5.199888 1.199896 180)
			(size 0.4064 0.4064)
			(layers "F.Cu" "F.Mask" "F.Paste")
			(net "BOARD_TYPE_2_ADC_R")
		)
		(pad "K3" smd circle
			(at -4.400042 1.199896 180)
			(size 0.4064 0.4064)
			(layers "F.Cu" "F.Mask" "F.Paste")
			(net "BOARD_TYPE_0_ADC_R")
		)
		(pad "K4" smd circle
			(at -3.599942 1.199896 180)
			(size 0.4064 0.4064)
			(layers "F.Cu" "F.Mask" "F.Paste")
			(net "BOARD_TYPE_1_ADC_R")
		)
		(pad "K5" smd circle
			(at -2.800096 1.199896 180)
			(size 0.4064 0.4064)
			(layers "F.Cu" "F.Mask" "F.Paste")
			(net "P3V3_BIC_ADCAV33")
		)
		(pad "K6" smd circle
			(at -1.999996 1.199896 180)
			(size 0.4064 0.4064)
			(layers "F.Cu" "F.Mask" "F.Paste")
			(net "GND")
		)
		(pad "K7" smd circle
			(at -1.199896 1.199896 180)
			(size 0.4064 0.4064)
			(layers "F.Cu" "F.Mask" "F.Paste")
			(net "GND")
		)
		(pad "K8" smd circle
			(at -0.40005 1.199896 180)
			(size 0.4064 0.4064)
			(layers "F.Cu" "F.Mask" "F.Paste")
			(net "GND")
		)
		(pad "K9" smd circle
			(at 0.40005 1.199896 180)
			(size 0.4064 0.4064)
			(layers "F.Cu" "F.Mask" "F.Paste")
			(net "GND")
		)
		(pad "K10" smd circle
			(at 1.199896 1.199896 180)
			(size 0.4064 0.4064)
			(layers "F.Cu" "F.Mask" "F.Paste")
			(net "GND")
		)
		(pad "K11" smd circle
			(at 1.999996 1.199896 180)
			(size 0.4064 0.4064)
			(layers "F.Cu" "F.Mask" "F.Paste")
			(net "GND")
		)
		(pad "K12" smd circle
			(at 2.800096 1.199896 180)
			(size 0.4064 0.4064)
			(layers "F.Cu" "F.Mask" "F.Paste")
			(net "P1V2_AUX")
		)
		(pad "K13" smd circle
			(at 3.599942 1.199896 180)
			(size 0.4064 0.4064)
			(layers "F.Cu" "F.Mask" "F.Paste")
			(net "P3V3_AUX")
		)
		(pad "K14" smd circle
			(at 4.400042 1.199896 180)
			(size 0.4064 0.4064)
			(layers "F.Cu" "F.Mask" "F.Paste")
			(net "SMB_PEX_SCL")
		)
		(pad "K15" smd circle
			(at 5.199888 1.199896 180)
			(size 0.4064 0.4064)
			(layers "F.Cu" "F.Mask" "F.Paste")
			(net "SMB_PEX_SDA")
		)
		(pad "K16" smd circle
			(at 5.999988 1.199896 180)
			(size 0.4064 0.4064)
			(layers "F.Cu" "F.Mask" "F.Paste")
			(net "SMB_BIC_I2C9_SSD_MUX_SDA")
		)
		(pad "L1" smd circle
			(at -5.999988 1.999996 180)
			(size 0.4064 0.4064)
			(layers "F.Cu" "F.Mask" "F.Paste")
			(net "PRSNT_SSD9_R_N")
		)
		(pad "L2" smd circle
			(at -5.199888 1.999996 180)
			(size 0.4064 0.4064)
			(layers "F.Cu" "F.Mask" "F.Paste")
			(net "PRSNT_SSD8_R_N")
		)
		(pad "L3" smd circle
			(at -4.400042 1.999996 180)
			(size 0.4064 0.4064)
			(layers "F.Cu" "F.Mask" "F.Paste")
			(net "SSD13_PWRDIS_BIC")
		)
		(pad "L4" smd circle
			(at -3.599942 1.999996 180)
			(size 0.4064 0.4064)
			(layers "F.Cu" "F.Mask" "F.Paste")
			(net "SSD14_PWRDIS_BIC")
		)
		(pad "L5" smd circle
			(at -2.800096 1.999996 180)
			(size 0.4064 0.4064)
			(layers "F.Cu" "F.Mask" "F.Paste")
			(net "P3V3_AUX")
		)
		(pad "L6" smd circle
			(at -1.999996 1.999996 180)
			(size 0.4064 0.4064)
			(layers "F.Cu" "F.Mask" "F.Paste")
			(net "GND")
		)
		(pad "L7" smd circle
			(at -1.199896 1.999996 180)
			(size 0.4064 0.4064)
			(layers "F.Cu" "F.Mask" "F.Paste")
			(net "GND")
		)
		(pad "L8" smd circle
			(at -0.40005 1.999996 180)
			(size 0.4064 0.4064)
			(layers "F.Cu" "F.Mask" "F.Paste")
			(net "GND")
		)
		(pad "L9" smd circle
			(at 0.40005 1.999996 180)
			(size 0.4064 0.4064)
			(layers "F.Cu" "F.Mask" "F.Paste")
			(net "GND")
		)
		(pad "L10" smd circle
			(at 1.199896 1.999996 180)
			(size 0.4064 0.4064)
			(layers "F.Cu" "F.Mask" "F.Paste")
			(net "GND")
		)
		(pad "L11" smd circle
			(at 1.999996 1.999996 180)
			(size 0.4064 0.4064)
			(layers "F.Cu" "F.Mask" "F.Paste")
			(net "GND")
		)
		(pad "L12" smd circle
			(at 2.800096 1.999996 180)
			(size 0.4064 0.4064)
			(layers "F.Cu" "F.Mask" "F.Paste")
			(net "P3V3_AUX")
		)
		(pad "L13" smd circle
			(at 3.599942 1.999996 180)
			(size 0.4064 0.4064)
			(layers "F.Cu" "F.Mask" "F.Paste")
			(net "P3V3_AUX")
		)
		(pad "L14" smd circle
			(at 4.400042 1.999996 180)
			(size 0.4064 0.4064)
			(layers "F.Cu" "F.Mask" "F.Paste")
			(net "SMB_BIC_FPGA_R2_SCL")
		)
		(pad "L15" smd circle
			(at 5.199888 1.999996 180)
			(size 0.4064 0.4064)
			(layers "F.Cu" "F.Mask" "F.Paste")
			(net "SMB_BIC_FPGA_R2_SDA")
		)
		(pad "L16" smd circle
			(at 5.999988 1.999996 180)
			(size 0.4064 0.4064)
			(layers "F.Cu" "F.Mask" "F.Paste")
			(net "SMB_BIC_I2C9_SSD_MUX_SCL")
		)
		(pad "M1" smd circle
			(at -5.999988 2.800096 180)
			(size 0.4064 0.4064)
			(layers "F.Cu" "F.Mask" "F.Paste")
			(net "PRSNT_SSD12_R_N")
		)
		(pad "M2" smd circle
			(at -5.199888 2.800096 180)
			(size 0.4064 0.4064)
			(layers "F.Cu" "F.Mask" "F.Paste")
			(net "PRSNT_SSD11_R_N")
		)
		(pad "M3" smd circle
			(at -4.400042 2.800096 180)
			(size 0.4064 0.4064)
			(layers "F.Cu" "F.Mask" "F.Paste")
			(net "PRSNT_SSD10_R_N")
		)
		(pad "M4" smd circle
			(at -3.599942 2.800096 180)
			(size 0.4064 0.4064)
			(layers "F.Cu" "F.Mask" "F.Paste")
			(net "SSD15_PWRDIS_BIC")
		)
		(pad "M5" smd circle
			(at -2.800096 2.800096 180)
			(size 0.4064 0.4064)
			(layers "F.Cu" "F.Mask" "F.Paste")
			(net "PRSNT_SSD6_R_N")
		)
		(pad "M6" smd circle
			(at -1.999996 2.800096 180)
			(size 0.4064 0.4064)
			(layers "F.Cu" "F.Mask" "F.Paste")
			(net "P1V2_AUX")
		)
		(pad "M7" smd circle
			(at -1.199896 2.800096 180)
			(size 0.4064 0.4064)
			(layers "F.Cu" "F.Mask" "F.Paste")
			(net "GND")
		)
		(pad "M8" smd circle
			(at -0.40005 2.800096 180)
			(size 0.4064 0.4064)
			(layers "F.Cu" "F.Mask" "F.Paste")
			(net "GND")
		)
		(pad "M9" smd circle
			(at 0.40005 2.800096 180)
			(size 0.4064 0.4064)
			(layers "F.Cu" "F.Mask" "F.Paste")
			(net "GND")
		)
		(pad "M10" smd circle
			(at 1.199896 2.800096 180)
			(size 0.4064 0.4064)
			(layers "F.Cu" "F.Mask" "F.Paste")
			(net "GND")
		)
		(pad "M11" smd circle
			(at 1.999996 2.800096 180)
			(size 0.4064 0.4064)
			(layers "F.Cu" "F.Mask" "F.Paste")
			(net "GND")
		)
		(pad "M12" smd circle
			(at 2.800096 2.800096 180)
			(size 0.4064 0.4064)
			(layers "F.Cu" "F.Mask" "F.Paste")
			(net "BIC_FORCE_THROTTLE_N")
		)
		(pad "M13" smd circle
			(at 3.599942 2.800096 180)
			(size 0.4064 0.4064)
			(layers "F.Cu" "F.Mask" "F.Paste")
			(net "SMB_FIO_SCL")
		)
		(pad "M14" smd circle
			(at 4.400042 2.800096 180)
			(size 0.4064 0.4064)
			(layers "F.Cu" "F.Mask" "F.Paste")
			(net "SMB_BIC_I2C6_SDA")
		)
		(pad "M15" smd circle
			(at 5.199888 2.800096 180)
			(size 0.4064 0.4064)
			(layers "F.Cu" "F.Mask" "F.Paste")
			(net "I3C_MB_SCL")
		)
		(pad "M16" smd circle
			(at 5.999988 2.800096 180)
			(size 0.4064 0.4064)
			(layers "F.Cu" "F.Mask" "F.Paste")
			(net "I3C_MB_SDA")
		)
		(pad "N1" smd circle
			(at -5.999988 3.599942 180)
			(size 0.4064 0.4064)
			(layers "F.Cu" "F.Mask" "F.Paste")
			(net "PRSNT_SSD15_R_N")
		)
		(pad "N2" smd circle
			(at -5.199888 3.599942 180)
			(size 0.4064 0.4064)
			(layers "F.Cu" "F.Mask" "F.Paste")
			(net "PRSNT_SSD14_R_N")
		)
		(pad "N3" smd circle
			(at -4.400042 3.599942 180)
			(size 0.4064 0.4064)
			(layers "F.Cu" "F.Mask" "F.Paste")
			(net "PRSNT_SSD13_R_N")
		)
		(pad "N4" smd circle
			(at -3.599942 3.599942 180)
			(size 0.4064 0.4064)
			(layers "F.Cu" "F.Mask" "F.Paste")
			(net "PRSNT_NIC0_R_N")
		)
		(pad "N5" smd circle
			(at -2.800096 3.599942 180)
			(size 0.4064 0.4064)
			(layers "F.Cu" "F.Mask" "F.Paste")
			(net "PRSNT_SSD4_R_N")
		)
		(pad "N6" smd circle
			(at -1.999996 3.599942 180)
			(size 0.4064 0.4064)
			(layers "F.Cu" "F.Mask" "F.Paste")
			(net "SSD3_PWRDIS_BIC")
		)
		(pad "N7" smd circle
			(at -1.199896 3.599942 180)
			(size 0.4064 0.4064)
			(layers "F.Cu" "F.Mask" "F.Paste")
			(net "P3V3_AUX")
		)
		(pad "N8" smd circle
			(at -0.40005 3.599942 180)
			(size 0.4064 0.4064)
			(layers "F.Cu" "F.Mask" "F.Paste")
			(net "P1V2_AUX")
		)
		(pad "N9" smd circle
			(at 0.40005 3.599942 180)
			(size 0.4064 0.4064)
			(layers "F.Cu" "F.Mask" "F.Paste")
			(net "P1V2_AUX")
		)
		(pad "N10" smd circle
			(at 1.199896 3.599942 180)
			(size 0.4064 0.4064)
			(layers "F.Cu" "F.Mask" "F.Paste")
			(net "P3V3_AUX")
		)
		(pad "N11" smd circle
			(at 1.999996 3.599942 180)
			(size 0.4064 0.4064)
			(layers "F.Cu" "F.Mask" "F.Paste")
			(net "NIC7_MAIN_PWR_BIC_EN")
		)
		(pad "N12" smd circle
			(at 2.800096 3.599942 180)
			(size 0.4064 0.4064)
			(layers "F.Cu" "F.Mask" "F.Paste")
			(net "PRSNT_DBV2_SLIMSAS_R")
		)
		(pad "N13" smd circle
			(at 3.599942 3.599942 180)
			(size 0.4064 0.4064)
			(layers "F.Cu" "F.Mask" "F.Paste")
			(net "GND")
		)
		(pad "N14" smd circle
			(at 4.400042 3.599942 180)
			(size 0.4064 0.4064)
			(layers "F.Cu" "F.Mask" "F.Paste")
			(net "SMB_NIC1_SDA")
		)
		(pad "N15" smd circle
			(at 5.199888 3.599942 180)
			(size 0.4064 0.4064)
			(layers "F.Cu" "F.Mask" "F.Paste")
			(net "SMB_FIO_SDA")
		)
		(pad "N16" smd circle
			(at 5.999988 3.599942 180)
			(size 0.4064 0.4064)
			(layers "F.Cu" "F.Mask" "F.Paste")
			(net "SMB_BIC_I2C6_SCL")
		)
		(pad "P1" smd circle
			(at -5.999988 4.400042 180)
			(size 0.4064 0.4064)
			(layers "F.Cu" "F.Mask" "F.Paste")
			(net "PRSNT_NIC2_R_N")
		)
		(pad "P2" smd circle
			(at -5.199888 4.400042 180)
			(size 0.4064 0.4064)
			(layers "F.Cu" "F.Mask" "F.Paste")
			(net "PRSNT_NIC4_R_N")
		)
		(pad "P3" smd circle
			(at -4.400042 4.400042 180)
			(size 0.4064 0.4064)
			(layers "F.Cu" "F.Mask" "F.Paste")
			(net "PRSNT_NIC5_R_N")
		)
		(pad "P4" smd circle
			(at -3.599942 4.400042 180)
			(size 0.4064 0.4064)
			(layers "F.Cu" "F.Mask" "F.Paste")
			(net "PRSNT_NIC1_R_N")
		)
		(pad "P5" smd circle
			(at -2.800096 4.400042 180)
			(size 0.4064 0.4064)
			(layers "F.Cu" "F.Mask" "F.Paste")
			(net "PRSNT_NIC3_R_N")
		)
		(pad "P6" smd circle
			(at -1.999996 4.400042 180)
			(size 0.4064 0.4064)
			(layers "F.Cu" "F.Mask" "F.Paste")
			(net "PRSNT_SSD5_R_N")
		)
		(pad "P7" smd circle
			(at -1.199896 4.400042 180)
			(size 0.4064 0.4064)
			(layers "F.Cu" "F.Mask" "F.Paste")
			(net "SSD2_PWRDIS_BIC")
		)
		(pad "P8" smd circle
			(at -0.40005 4.400042 180)
			(size 0.4064 0.4064)
			(layers "F.Cu" "F.Mask" "F.Paste")
			(net "SSD4_PWRDIS_BIC")
		)
		(pad "P9" smd circle
			(at 0.40005 4.400042 180)
			(size 0.4064 0.4064)
			(layers "F.Cu" "F.Mask" "F.Paste")
			(net "NIC1_MAIN_PWR_BIC_EN")
		)
		(pad "P10" smd circle
			(at 1.199896 4.400042 180)
			(size 0.4064 0.4064)
			(layers "F.Cu" "F.Mask" "F.Paste")
			(net "NIC5_MAIN_PWR_BIC_EN")
		)
		(pad "P11" smd circle
			(at 1.999996 4.400042 180)
			(size 0.4064 0.4064)
			(layers "F.Cu" "F.Mask" "F.Paste")
			(net "BOARD_ID1")
		)
		(pad "P12" smd circle
			(at 2.800096 4.400042 180)
			(size 0.4064 0.4064)
			(layers "F.Cu" "F.Mask" "F.Paste")
			(net "SMB_NIC0_SDA")
		)
		(pad "P13" smd circle
			(at 3.599942 4.400042 180)
			(size 0.4064 0.4064)
			(layers "F.Cu" "F.Mask" "F.Paste")
			(net "SMB_NIC1_SCL")
		)
		(pad "P14" smd circle
			(at 4.400042 4.400042 180)
			(size 0.4064 0.4064)
			(layers "F.Cu" "F.Mask" "F.Paste")
			(net "RST_PEX_MUX_N")
		)
		(pad "P15" smd circle
			(at 5.199888 4.400042 180)
			(size 0.4064 0.4064)
			(layers "F.Cu" "F.Mask" "F.Paste")
			(net "SMB_NIC3_SCL")
		)
	)
)
